(kicad_pcb
	(version 20260206)
	(generator "pcbnew")
	(generator_version "10.0")
	(general
		(thickness 1.6)
		(legacy_teardrops no)
	)
	(paper "A4")
	(title_block
		(title "03242023_DA0F0TMBIJ0_F0T_Motherboard_J_brd_V01_OCP.brd")
		(comment 1 "Grand Teton / footprints 5830-5835 of 6105")
	)
	(layers
		(0 "F.Cu" signal "TOP")
		(4 "In1.Cu" signal "GND")
		(6 "In2.Cu" signal "IN1")
		(8 "In3.Cu" signal "GND1")
		(10 "In4.Cu" signal "IN2")
		(12 "In5.Cu" signal "GND2")
		(14 "In6.Cu" signal "IN3")
		(16 "In7.Cu" signal "GND3")
		(18 "In8.Cu" signal "VCC")
		(20 "In9.Cu" signal "VCC1")
		(22 "In10.Cu" signal "GND4")
		(24 "In11.Cu" signal "IN4")
		(26 "In12.Cu" signal "GND5")
		(28 "In13.Cu" signal "IN5")
		(30 "In14.Cu" signal "GND6")
		(32 "In15.Cu" signal "IN6")
		(34 "In16.Cu" signal "GND7")
		(2 "B.Cu" signal "BOTTOM")
		(9 "F.Adhes" user "F.Adhesive")
		(11 "B.Adhes" user "B.Adhesive")
		(13 "F.Paste" user "Package Geometry/Pastemask Top")
		(15 "B.Paste" user "Package Geometry/Pastemask Bottom")
		(5 "F.SilkS" user "Ref Des/Silkscreen Top")
		(7 "B.SilkS" user "Ref Des/Silkscreen Bottom")
		(1 "F.Mask" user "Board Geometry/Soldermask Top")
		(3 "B.Mask" user "Board Geometry/Soldermask Bottom")
		(17 "Dwgs.User" user "User.Drawings")
		(19 "Cmts.User" user "User.Comments")
		(21 "Eco1.User" user "User.Eco1")
		(23 "Eco2.User" user "User.Eco2")
		(25 "Edge.Cuts" user "Board Geometry/Outline")
		(27 "Margin" user)
		(31 "F.CrtYd" user "Package Geometry/Place Bound Top")
		(29 "B.CrtYd" user "Package Geometry/Place Bound Bottom")
		(35 "F.Fab" user "Ref Des/Assembly Top")
		(33 "B.Fab" user "Ref Des/Assembly Bottom")
	)
	(footprint ""
		(layer "B.Cu")
		(at 263.637014 -319.263776 180)
		(property "Reference" "C23"
			(at 0 0 0)
			(layer "B.SilkS")
			(hide yes)
			(effects
				(font
					(size 1.27 1.27)
				)
				(justify mirror)
			)
		)
		(property "Value" ""
			(at 0 0 0)
			(layer "B.Fab")
			(effects
				(font
					(size 1.27 1.27)
				)
				(justify mirror)
			)
		)
		(duplicate_pad_numbers_are_jumpers no)
		(fp_line
			(start 0.7874 0.4064)
			(end 0.7874 -0.4064)
			(stroke
				(width 0.1524)
				(type default)
			)
			(layer "B.SilkS")
		)
		(fp_line
			(start 0.7874 -0.4064)
			(end -0.7874 -0.4064)
			(stroke
				(width 0.1524)
				(type default)
			)
			(layer "B.SilkS")
		)
		(fp_line
			(start -0.7874 0.4064)
			(end 0.7874 0.4064)
			(stroke
				(width 0.1524)
				(type default)
			)
			(layer "B.SilkS")
		)
		(fp_line
			(start -0.7874 -0.4064)
			(end -0.7874 0.4064)
			(stroke
				(width 0.1524)
				(type default)
			)
			(layer "B.SilkS")
		)
		(fp_line
			(start 0.67945 0.3048)
			(end 0.67945 -0.305054)
			(stroke
				(width 0.1)
				(type default)
			)
			(layer "B.Fab")
		)
		(fp_line
			(start 0.67945 -0.305054)
			(end 0.12065 -0.305054)
			(stroke
				(width 0.1)
				(type default)
			)
			(layer "B.Fab")
		)
		(fp_line
			(start 0.12065 0.3048)
			(end 0.67945 0.3048)
			(stroke
				(width 0.1)
				(type default)
			)
			(layer "B.Fab")
		)
		(fp_line
			(start 0.12065 0.2794)
			(end 0.12065 0.3048)
			(stroke
				(width 0.1)
				(type default)
			)
			(layer "B.Fab")
		)
		(fp_line
			(start 0.12065 -0.2794)
			(end -0.12065 -0.2794)
			(stroke
				(width 0.1)
				(type default)
			)
			(layer "B.Fab")
		)
		(fp_line
			(start 0.12065 -0.305054)
			(end 0.12065 -0.2794)
			(stroke
				(width 0.1)
				(type default)
			)
			(layer "B.Fab")
		)
		(fp_line
			(start -0.120396 0.3048)
			(end -0.120396 0.2794)
			(stroke
				(width 0.1)
				(type default)
			)
			(layer "B.Fab")
		)
		(fp_line
			(start -0.120396 0.2794)
			(end 0.12065 0.2794)
			(stroke
				(width 0.1)
				(type default)
			)
			(layer "B.Fab")
		)
		(fp_line
			(start -0.12065 -0.2794)
			(end -0.12065 -0.3048)
			(stroke
				(width 0.1)
				(type default)
			)
			(layer "B.Fab")
		)
		(fp_line
			(start -0.12065 -0.3048)
			(end -0.67945 -0.3048)
			(stroke
				(width 0.1)
				(type default)
			)
			(layer "B.Fab")
		)
		(fp_line
			(start -0.67945 0.3048)
			(end -0.120396 0.3048)
			(stroke
				(width 0.1)
				(type default)
			)
			(layer "B.Fab")
		)
		(fp_line
			(start -0.67945 -0.3048)
			(end -0.67945 0.3048)
			(stroke
				(width 0.1)
				(type default)
			)
			(layer "B.Fab")
		)
		(pad "1" smd circle
			(at 0.40005 0)
			(size 0 0)
			(layers "B.Cu" "B.Mask" "B.Paste")
			(net "P3V3_AUX")
		)
		(pad "2" smd circle
			(at -0.40005 0)
			(size 0 0)
			(layers "B.Cu" "B.Mask" "B.Paste")
			(net "GND")
		)
	)
	(footprint ""
		(layer "B.Cu")
		(at 128.85928 -31.542228 90)
		(property "Reference" "R4273"
			(at 0 0 90)
			(layer "B.SilkS")
			(hide yes)
			(effects
				(font
					(size 1.27 1.27)
				)
				(justify mirror)
			)
		)
		(property "Value" ""
			(at 0 0 90)
			(layer "B.Fab")
			(effects
				(font
					(size 1.27 1.27)
				)
				(justify mirror)
			)
		)
		(duplicate_pad_numbers_are_jumpers no)
		(fp_line
			(start 0.7874 -0.4064)
			(end -0.7874 -0.4064)
			(stroke
				(width 0.1524)
				(type default)
			)
			(layer "B.SilkS")
		)
		(fp_line
			(start -0.7874 -0.4064)
			(end -0.7874 0.4064)
			(stroke
				(width 0.1524)
				(type default)
			)
			(layer "B.SilkS")
		)
		(fp_line
			(start 0.7874 0.4064)
			(end 0.7874 -0.4064)
			(stroke
				(width 0.1524)
				(type default)
			)
			(layer "B.SilkS")
		)
		(fp_line
			(start -0.7874 0.4064)
			(end 0.7874 0.4064)
			(stroke
				(width 0.1524)
				(type default)
			)
			(layer "B.SilkS")
		)
		(fp_line
			(start 0.67945 -0.305054)
			(end 0.12065 -0.305054)
			(stroke
				(width 0.1)
				(type default)
			)
			(layer "B.Fab")
		)
		(fp_line
			(start 0.12065 -0.305054)
			(end 0.12065 -0.2794)
			(stroke
				(width 0.1)
				(type default)
			)
			(layer "B.Fab")
		)
		(fp_line
			(start -0.12065 -0.3048)
			(end -0.67945 -0.3048)
			(stroke
				(width 0.1)
				(type default)
			)
			(layer "B.Fab")
		)
		(fp_line
			(start -0.67945 -0.3048)
			(end -0.67945 0.3048)
			(stroke
				(width 0.1)
				(type default)
			)
			(layer "B.Fab")
		)
		(fp_line
			(start 0.12065 -0.2794)
			(end -0.12065 -0.2794)
			(stroke
				(width 0.1)
				(type default)
			)
			(layer "B.Fab")
		)
		(fp_line
			(start -0.12065 -0.2794)
			(end -0.12065 -0.3048)
			(stroke
				(width 0.1)
				(type default)
			)
			(layer "B.Fab")
		)
		(fp_line
			(start 0.12065 0.2794)
			(end 0.12065 0.3048)
			(stroke
				(width 0.1)
				(type default)
			)
			(layer "B.Fab")
		)
		(fp_line
			(start -0.120396 0.2794)
			(end 0.12065 0.2794)
			(stroke
				(width 0.1)
				(type default)
			)
			(layer "B.Fab")
		)
		(fp_line
			(start 0.67945 0.3048)
			(end 0.67945 -0.305054)
			(stroke
				(width 0.1)
				(type default)
			)
			(layer "B.Fab")
		)
		(fp_line
			(start 0.12065 0.3048)
			(end 0.67945 0.3048)
			(stroke
				(width 0.1)
				(type default)
			)
			(layer "B.Fab")
		)
		(fp_line
			(start -0.120396 0.3048)
			(end -0.120396 0.2794)
			(stroke
				(width 0.1)
				(type default)
			)
			(layer "B.Fab")
		)
		(fp_line
			(start -0.67945 0.3048)
			(end -0.120396 0.3048)
			(stroke
				(width 0.1)
				(type default)
			)
			(layer "B.Fab")
		)
		(pad "1" smd circle
			(at 0.40005 0 270)
			(size 0 0)
			(layers "B.Cu" "B.Mask" "B.Paste")
			(net "P3V3_AUX")
		)
		(pad "2" smd circle
			(at -0.40005 0 270)
			(size 0 0)
			(layers "B.Cu" "B.Mask" "B.Paste")
			(net "FM_USB3_1_FGB")
		)
	)
	(footprint ""
		(layer "B.Cu")
		(at 315.110622 -54.219348)
		(property "Reference" "R4109"
			(at 0 0 0)
			(layer "B.SilkS")
			(hide yes)
			(effects
				(font
					(size 1.27 1.27)
				)
				(justify mirror)
			)
		)
		(property "Value" ""
			(at 0 0 0)
			(layer "B.Fab")
			(effects
				(font
					(size 1.27 1.27)
				)
				(justify mirror)
			)
		)
		(duplicate_pad_numbers_are_jumpers no)
		(fp_line
			(start -0.7874 -0.4064)
			(end -0.7874 0.4064)
			(stroke
				(width 0.1524)
				(type default)
			)
			(layer "B.SilkS")
		)
		(fp_line
			(start -0.7874 0.4064)
			(end 0.7874 0.4064)
			(stroke
				(width 0.1524)
				(type default)
			)
			(layer "B.SilkS")
		)
		(fp_line
			(start 0.7874 -0.4064)
			(end -0.7874 -0.4064)
			(stroke
				(width 0.1524)
				(type default)
			)
			(layer "B.SilkS")
		)
		(fp_line
			(start 0.7874 0.4064)
			(end 0.7874 -0.4064)
			(stroke
				(width 0.1524)
				(type default)
			)
			(layer "B.SilkS")
		)
		(fp_line
			(start -0.67945 -0.3048)
			(end -0.67945 0.3048)
			(stroke
				(width 0.1)
				(type default)
			)
			(layer "B.Fab")
		)
		(fp_line
			(start -0.67945 0.3048)
			(end -0.120396 0.3048)
			(stroke
				(width 0.1)
				(type default)
			)
			(layer "B.Fab")
		)
		(fp_line
			(start -0.12065 -0.3048)
			(end -0.67945 -0.3048)
			(stroke
				(width 0.1)
				(type default)
			)
			(layer "B.Fab")
		)
		(fp_line
			(start -0.12065 -0.2794)
			(end -0.12065 -0.3048)
			(stroke
				(width 0.1)
				(type default)
			)
			(layer "B.Fab")
		)
		(fp_line
			(start -0.120396 0.2794)
			(end 0.12065 0.2794)
			(stroke
				(width 0.1)
				(type default)
			)
			(layer "B.Fab")
		)
		(fp_line
			(start -0.120396 0.3048)
			(end -0.120396 0.2794)
			(stroke
				(width 0.1)
				(type default)
			)
			(layer "B.Fab")
		)
		(fp_line
			(start 0.12065 -0.305054)
			(end 0.12065 -0.2794)
			(stroke
				(width 0.1)
				(type default)
			)
			(layer "B.Fab")
		)
		(fp_line
			(start 0.12065 -0.2794)
			(end -0.12065 -0.2794)
			(stroke
				(width 0.1)
				(type default)
			)
			(layer "B.Fab")
		)
		(fp_line
			(start 0.12065 0.2794)
			(end 0.12065 0.3048)
			(stroke
				(width 0.1)
				(type default)
			)
			(layer "B.Fab")
		)
		(fp_line
			(start 0.12065 0.3048)
			(end 0.67945 0.3048)
			(stroke
				(width 0.1)
				(type default)
			)
			(layer "B.Fab")
		)
		(fp_line
			(start 0.67945 -0.305054)
			(end 0.12065 -0.305054)
			(stroke
				(width 0.1)
				(type default)
			)
			(layer "B.Fab")
		)
		(fp_line
			(start 0.67945 0.3048)
			(end 0.67945 -0.305054)
			(stroke
				(width 0.1)
				(type default)
			)
			(layer "B.Fab")
		)
		(pad "1" smd circle
			(at 0.40005 0 180)
			(size 0 0)
			(layers "B.Cu" "B.Mask" "B.Paste")
			(net "PD_GPP_I_15")
		)
		(pad "2" smd circle
			(at -0.40005 0 180)
			(size 0 0)
			(layers "B.Cu" "B.Mask" "B.Paste")
			(net "GND")
		)
	)
	(footprint ""
		(layer "B.Cu")
		(at 344.820748 -31.527242)
		(property "Reference" "R502"
			(at 0 0 0)
			(layer "B.SilkS")
			(hide yes)
			(effects
				(font
					(size 1.27 1.27)
				)
				(justify mirror)
			)
		)
		(property "Value" ""
			(at 0 0 0)
			(layer "B.Fab")
			(effects
				(font
					(size 1.27 1.27)
				)
				(justify mirror)
			)
		)
		(duplicate_pad_numbers_are_jumpers no)
		(fp_line
			(start -0.7874 -0.4064)
			(end -0.7874 0.4064)
			(stroke
				(width 0.1524)
				(type default)
			)
			(layer "B.SilkS")
		)
		(fp_line
			(start -0.7874 0.4064)
			(end 0.7874 0.4064)
			(stroke
				(width 0.1524)
				(type default)
			)
			(layer "B.SilkS")
		)
		(fp_line
			(start 0.7874 -0.4064)
			(end -0.7874 -0.4064)
			(stroke
				(width 0.1524)
				(type default)
			)
			(layer "B.SilkS")
		)
		(fp_line
			(start 0.7874 0.4064)
			(end 0.7874 -0.4064)
			(stroke
				(width 0.1524)
				(type default)
			)
			(layer "B.SilkS")
		)
		(fp_line
			(start -0.67945 -0.3048)
			(end -0.67945 0.3048)
			(stroke
				(width 0.1)
				(type default)
			)
			(layer "B.Fab")
		)
		(fp_line
			(start -0.67945 0.3048)
			(end -0.120396 0.3048)
			(stroke
				(width 0.1)
				(type default)
			)
			(layer "B.Fab")
		)
		(fp_line
			(start -0.12065 -0.3048)
			(end -0.67945 -0.3048)
			(stroke
				(width 0.1)
				(type default)
			)
			(layer "B.Fab")
		)
		(fp_line
			(start -0.12065 -0.2794)
			(end -0.12065 -0.3048)
			(stroke
				(width 0.1)
				(type default)
			)
			(layer "B.Fab")
		)
		(fp_line
			(start -0.120396 0.2794)
			(end 0.12065 0.2794)
			(stroke
				(width 0.1)
				(type default)
			)
			(layer "B.Fab")
		)
		(fp_line
			(start -0.120396 0.3048)
			(end -0.120396 0.2794)
			(stroke
				(width 0.1)
				(type default)
			)
			(layer "B.Fab")
		)
		(fp_line
			(start 0.12065 -0.305054)
			(end 0.12065 -0.2794)
			(stroke
				(width 0.1)
				(type default)
			)
			(layer "B.Fab")
		)
		(fp_line
			(start 0.12065 -0.2794)
			(end -0.12065 -0.2794)
			(stroke
				(width 0.1)
				(type default)
			)
			(layer "B.Fab")
		)
		(fp_line
			(start 0.12065 0.2794)
			(end 0.12065 0.3048)
			(stroke
				(width 0.1)
				(type default)
			)
			(layer "B.Fab")
		)
		(fp_line
			(start 0.12065 0.3048)
			(end 0.67945 0.3048)
			(stroke
				(width 0.1)
				(type default)
			)
			(layer "B.Fab")
		)
		(fp_line
			(start 0.67945 -0.305054)
			(end 0.12065 -0.305054)
			(stroke
				(width 0.1)
				(type default)
			)
			(layer "B.Fab")
		)
		(fp_line
			(start 0.67945 0.3048)
			(end 0.67945 -0.305054)
			(stroke
				(width 0.1)
				(type default)
			)
			(layer "B.Fab")
		)
		(pad "1" smd circle
			(at 0.40005 0 180)
			(size 0 0)
			(layers "B.Cu" "B.Mask" "B.Paste")
			(net "P3V3_AUX")
		)
		(pad "2" smd circle
			(at -0.40005 0 180)
			(size 0 0)
			(layers "B.Cu" "B.Mask" "B.Paste")
			(net "FM_PCH_CONSENT_STRAP_N")
		)
	)
	(footprint ""
		(layer "B.Cu")
		(at 355.397308 -259.531866 90)
		(property "Reference" "C505"
			(at 0 0 90)
			(layer "B.SilkS")
			(hide yes)
			(effects
				(font
					(size 1.27 1.27)
				)
				(justify mirror)
			)
		)
		(property "Value" ""
			(at 0 0 90)
			(layer "B.Fab")
			(effects
				(font
					(size 1.27 1.27)
				)
				(justify mirror)
			)
		)
		(duplicate_pad_numbers_are_jumpers no)
		(fp_line
			(start 1.524 -0.762)
			(end -1.524 -0.762)
			(stroke
				(width 0.1524)
				(type default)
			)
			(layer "B.SilkS")
		)
		(fp_line
			(start -1.524 -0.762)
			(end -1.524 0.762)
			(stroke
				(width 0.1524)
				(type default)
			)
			(layer "B.SilkS")
		)
		(fp_line
			(start 1.524 0.762)
			(end 1.524 -0.762)
			(stroke
				(width 0.1524)
				(type default)
			)
			(layer "B.SilkS")
		)
		(fp_line
			(start -1.524 0.762)
			(end 1.524 0.762)
			(stroke
				(width 0.1524)
				(type default)
			)
			(layer "B.SilkS")
		)
		(fp_line
			(start 1.1049 -0.724916)
			(end 1.1049 0.724916)
			(stroke
				(width 0.1)
				(type default)
			)
			(layer "B.Fab")
		)
		(fp_line
			(start -1.1049 -0.724916)
			(end 1.1049 -0.724916)
			(stroke
				(width 0.1)
				(type default)
			)
			(layer "B.Fab")
		)
		(fp_line
			(start 1.1049 0.724916)
			(end -1.1049 0.724916)
			(stroke
				(width 0.1)
				(type default)
			)
			(layer "B.Fab")
		)
		(fp_line
			(start -1.1049 0.724916)
			(end -1.1049 -0.724916)
			(stroke
				(width 0.1)
				(type default)
			)
			(layer "B.Fab")
		)
		(pad "1" smd rect
			(at 0.889 0 90)
			(size 1.016 1.27)
			(layers "B.Cu" "B.Mask" "B.Paste")
			(net "PVCCFA_EHV_FIVRA_CPU0")
		)
		(pad "2" smd rect
			(at -0.889 0 90)
			(size 1.016 1.27)
			(layers "B.Cu" "B.Mask" "B.Paste")
			(net "GND")
		)
	)
	(footprint ""
		(layer "B.Cu")
		(at 64.637158 -192.96253 90)
		(property "Reference" "R137"
			(at 0 0 90)
			(layer "B.SilkS")
			(hide yes)
			(effects
				(font
					(size 1.27 1.27)
				)
				(justify mirror)
			)
		)
		(property "Value" ""
			(at 0 0 90)
			(layer "B.Fab")
			(effects
				(font
					(size 1.27 1.27)
				)
				(justify mirror)
			)
		)
		(duplicate_pad_numbers_are_jumpers no)
		(fp_line
			(start 0.7874 -0.4064)
			(end -0.7874 -0.4064)
			(stroke
				(width 0.1524)
				(type default)
			)
			(layer "B.SilkS")
		)
		(fp_line
			(start -0.7874 -0.4064)
			(end -0.7874 0.4064)
			(stroke
				(width 0.1524)
				(type default)
			)
			(layer "B.SilkS")
		)
		(fp_line
			(start 0.7874 0.4064)
			(end 0.7874 -0.4064)
			(stroke
				(width 0.1524)
				(type default)
			)
			(layer "B.SilkS")
		)
		(fp_line
			(start -0.7874 0.4064)
			(end 0.7874 0.4064)
			(stroke
				(width 0.1524)
				(type default)
			)
			(layer "B.SilkS")
		)
		(fp_line
			(start 0.67945 -0.305054)
			(end 0.12065 -0.305054)
			(stroke
				(width 0.1)
				(type default)
			)
			(layer "B.Fab")
		)
		(fp_line
			(start 0.12065 -0.305054)
			(end 0.12065 -0.2794)
			(stroke
				(width 0.1)
				(type default)
			)
			(layer "B.Fab")
		)
		(fp_line
			(start -0.12065 -0.3048)
			(end -0.67945 -0.3048)
			(stroke
				(width 0.1)
				(type default)
			)
			(layer "B.Fab")
		)
		(fp_line
			(start -0.67945 -0.3048)
			(end -0.67945 0.3048)
			(stroke
				(width 0.1)
				(type default)
			)
			(layer "B.Fab")
		)
		(fp_line
			(start 0.12065 -0.2794)
			(end -0.12065 -0.2794)
			(stroke
				(width 0.1)
				(type default)
			)
			(layer "B.Fab")
		)
		(fp_line
			(start -0.12065 -0.2794)
			(end -0.12065 -0.3048)
			(stroke
				(width 0.1)
				(type default)
			)
			(layer "B.Fab")
		)
		(fp_line
			(start 0.12065 0.2794)
			(end 0.12065 0.3048)
			(stroke
				(width 0.1)
				(type default)
			)
			(layer "B.Fab")
		)
		(fp_line
			(start -0.120396 0.2794)
			(end 0.12065 0.2794)
			(stroke
				(width 0.1)
				(type default)
			)
			(layer "B.Fab")
		)
		(fp_line
			(start 0.67945 0.3048)
			(end 0.67945 -0.305054)
			(stroke
				(width 0.1)
				(type default)
			)
			(layer "B.Fab")
		)
		(fp_line
			(start 0.12065 0.3048)
			(end 0.67945 0.3048)
			(stroke
				(width 0.1)
				(type default)
			)
			(layer "B.Fab")
		)
		(fp_line
			(start -0.120396 0.3048)
			(end -0.120396 0.2794)
			(stroke
				(width 0.1)
				(type default)
			)
			(layer "B.Fab")
		)
		(fp_line
			(start -0.67945 0.3048)
			(end -0.120396 0.3048)
			(stroke
				(width 0.1)
				(type default)
			)
			(layer "B.Fab")
		)
		(pad "1" smd circle
			(at 0.40005 0 270)
			(size 0 0)
			(layers "B.Cu" "B.Mask" "B.Paste")
			(net "PWRGD_DRAMPWRGD_CPU1_CD_LVC1_R2")
		)
		(pad "2" smd circle
			(at -0.40005 0 270)
			(size 0 0)
			(layers "B.Cu" "B.Mask" "B.Paste")
			(net "PVCCD_HV_CPU1")
		)
	)
)
